# S9S_MB_2U (Grand Teton) — schematic netlist excerpt (pin names and nets, part order shuffled) for the footprints in the layout excerpt that follows; sources: Cadence DE-HDL packaged netlist, KiCad conversion of 03242023_DA0F0TMBIJ0_F0T_Motherboard_J_brd_V01_OCP.brd

R773  Q_RES  1K 1% CHIP  pkg 0402LF  page 131 : A = JTAG_DBP_BOOT_HALT_N ; B = FM_ADR_MODE0
C2541  Q_CAP  0.22UF 25V 10% X7R  pkg C0402  page 259 : A = P3V3_AUX_EN ; B = GND
C1398  Q_CAP  47UF 4V 20% X6S  pkg C0805  page 75 : A = PVPP_HBM_CPU0 ; B = GND

(kicad_pcb
	(version 20260206)
	(generator "pcbnew")
	(generator_version "10.0")
	(general
		(thickness 1.6)
		(legacy_teardrops no)
	)
	(paper "A4")
	(title_block
		(title "03242023_DA0F0TMBIJ0_F0T_Motherboard_J_brd_V01_OCP.brd")
		(comment 1 "Grand Teton / footprints 4169-4171 of 6105")
	)
	(layers
		(0 "F.Cu" signal "TOP")
		(4 "In1.Cu" signal "GND")
		(6 "In2.Cu" signal "IN1")
		(8 "In3.Cu" signal "GND1")
		(10 "In4.Cu" signal "IN2")
		(12 "In5.Cu" signal "GND2")
		(14 "In6.Cu" signal "IN3")
		(16 "In7.Cu" signal "GND3")
		(18 "In8.Cu" signal "VCC")
		(20 "In9.Cu" signal "VCC1")
		(22 "In10.Cu" signal "GND4")
		(24 "In11.Cu" signal "IN4")
		(26 "In12.Cu" signal "GND5")
		(28 "In13.Cu" signal "IN5")
		(30 "In14.Cu" signal "GND6")
		(32 "In15.Cu" signal "IN6")
		(34 "In16.Cu" signal "GND7")
		(2 "B.Cu" signal "BOTTOM")
		(9 "F.Adhes" user "F.Adhesive")
		(11 "B.Adhes" user "B.Adhesive")
		(13 "F.Paste" user "Package Geometry/Pastemask Top")
		(15 "B.Paste" user "Package Geometry/Pastemask Bottom")
		(5 "F.SilkS" user "Ref Des/Silkscreen Top")
		(7 "B.SilkS" user "Ref Des/Silkscreen Bottom")
		(1 "F.Mask" user "Board Geometry/Soldermask Top")
		(3 "B.Mask" user "Board Geometry/Soldermask Bottom")
		(17 "Dwgs.User" user "User.Drawings")
		(19 "Cmts.User" user "User.Comments")
		(21 "Eco1.User" user "User.Eco1")
		(23 "Eco2.User" user "User.Eco2")
		(25 "Edge.Cuts" user "Board Geometry/Outline")
		(27 "Margin" user)
		(31 "F.CrtYd" user "Package Geometry/Place Bound Top")
		(29 "B.CrtYd" user "Package Geometry/Place Bound Bottom")
		(35 "F.Fab" user "Ref Des/Assembly Top")
		(33 "B.Fab" user "Ref Des/Assembly Bottom")
	)
	(footprint ""
		(layer "B.Cu")
		(at 404.002748 -59.939428 180)
		(property "Reference" "R773"
			(at 0 0 0)
			(layer "B.SilkS")
			(hide yes)
			(effects
				(font
					(size 1.27 1.27)
				)
				(justify mirror)
			)
		)
		(property "Value" ""
			(at 0 0 0)
			(layer "B.Fab")
			(effects
				(font
					(size 1.27 1.27)
				)
				(justify mirror)
			)
		)
		(duplicate_pad_numbers_are_jumpers no)
		(fp_line
			(start 0.7874 0.4064)
			(end 0.7874 -0.4064)
			(stroke
				(width 0.1524)
				(type default)
			)
			(layer "B.SilkS")
		)
		(fp_line
			(start 0.7874 -0.4064)
			(end -0.7874 -0.4064)
			(stroke
				(width 0.1524)
				(type default)
			)
			(layer "B.SilkS")
		)
		(fp_line
			(start -0.7874 0.4064)
			(end 0.7874 0.4064)
			(stroke
				(width 0.1524)
				(type default)
			)
			(layer "B.SilkS")
		)
		(fp_line
			(start -0.7874 -0.4064)
			(end -0.7874 0.4064)
			(stroke
				(width 0.1524)
				(type default)
			)
			(layer "B.SilkS")
		)
		(fp_line
			(start 0.67945 0.3048)
			(end 0.67945 -0.305054)
			(stroke
				(width 0.1)
				(type default)
			)
			(layer "B.Fab")
		)
		(fp_line
			(start 0.67945 -0.305054)
			(end 0.12065 -0.305054)
			(stroke
				(width 0.1)
				(type default)
			)
			(layer "B.Fab")
		)
		(fp_line
			(start 0.12065 0.3048)
			(end 0.67945 0.3048)
			(stroke
				(width 0.1)
				(type default)
			)
			(layer "B.Fab")
		)
		(fp_line
			(start 0.12065 0.2794)
			(end 0.12065 0.3048)
			(stroke
				(width 0.1)
				(type default)
			)
			(layer "B.Fab")
		)
		(fp_line
			(start 0.12065 -0.2794)
			(end -0.12065 -0.2794)
			(stroke
				(width 0.1)
				(type default)
			)
			(layer "B.Fab")
		)
		(fp_line
			(start 0.12065 -0.305054)
			(end 0.12065 -0.2794)
			(stroke
				(width 0.1)
				(type default)
			)
			(layer "B.Fab")
		)
		(fp_line
			(start -0.120396 0.3048)
			(end -0.120396 0.2794)
			(stroke
				(width 0.1)
				(type default)
			)
			(layer "B.Fab")
		)
		(fp_line
			(start -0.120396 0.2794)
			(end 0.12065 0.2794)
			(stroke
				(width 0.1)
				(type default)
			)
			(layer "B.Fab")
		)
		(fp_line
			(start -0.12065 -0.2794)
			(end -0.12065 -0.3048)
			(stroke
				(width 0.1)
				(type default)
			)
			(layer "B.Fab")
		)
		(fp_line
			(start -0.12065 -0.3048)
			(end -0.67945 -0.3048)
			(stroke
				(width 0.1)
				(type default)
			)
			(layer "B.Fab")
		)
		(fp_line
			(start -0.67945 0.3048)
			(end -0.120396 0.3048)
			(stroke
				(width 0.1)
				(type default)
			)
			(layer "B.Fab")
		)
		(fp_line
			(start -0.67945 -0.3048)
			(end -0.67945 0.3048)
			(stroke
				(width 0.1)
				(type default)
			)
			(layer "B.Fab")
		)
		(pad "1" smd circle
			(at 0.40005 0)
			(size 0 0)
			(layers "B.Cu" "B.Mask" "B.Paste")
			(net "JTAG_DBP_BOOT_HALT_N")
		)
		(pad "2" smd circle
			(at -0.40005 0)
			(size 0 0)
			(layers "B.Cu" "B.Mask" "B.Paste")
			(net "FM_ADR_MODE0")
		)
	)
	(footprint ""
		(layer "B.Cu")
		(at 391.416032 -340.08568)
		(property "Reference" "C1398"
			(at 0 0 0)
			(layer "B.SilkS")
			(hide yes)
			(effects
				(font
					(size 1.27 1.27)
				)
				(justify mirror)
			)
		)
		(property "Value" ""
			(at 0 0 0)
			(layer "B.Fab")
			(effects
				(font
					(size 1.27 1.27)
				)
				(justify mirror)
			)
		)
		(duplicate_pad_numbers_are_jumpers no)
		(fp_line
			(start -1.524 -0.762)
			(end -1.524 0.762)
			(stroke
				(width 0.1524)
				(type default)
			)
			(layer "B.SilkS")
		)
		(fp_line
			(start -1.524 0.762)
			(end 1.524 0.762)
			(stroke
				(width 0.1524)
				(type default)
			)
			(layer "B.SilkS")
		)
		(fp_line
			(start 1.524 -0.762)
			(end -1.524 -0.762)
			(stroke
				(width 0.1524)
				(type default)
			)
			(layer "B.SilkS")
		)
		(fp_line
			(start 1.524 0.762)
			(end 1.524 -0.762)
			(stroke
				(width 0.1524)
				(type default)
			)
			(layer "B.SilkS")
		)
		(fp_line
			(start -1.1049 -0.724916)
			(end 1.1049 -0.724916)
			(stroke
				(width 0.1)
				(type default)
			)
			(layer "B.Fab")
		)
		(fp_line
			(start -1.1049 0.724916)
			(end -1.1049 -0.724916)
			(stroke
				(width 0.1)
				(type default)
			)
			(layer "B.Fab")
		)
		(fp_line
			(start 1.1049 -0.724916)
			(end 1.1049 0.724916)
			(stroke
				(width 0.1)
				(type default)
			)
			(layer "B.Fab")
		)
		(fp_line
			(start 1.1049 0.724916)
			(end -1.1049 0.724916)
			(stroke
				(width 0.1)
				(type default)
			)
			(layer "B.Fab")
		)
		(pad "1" smd rect
			(at 0.889 0)
			(size 1.016 1.27)
			(layers "B.Cu" "B.Mask" "B.Paste")
			(net "PVPP_HBM_CPU0")
		)
		(pad "2" smd rect
			(at -0.889 0)
			(size 1.016 1.27)
			(layers "B.Cu" "B.Mask" "B.Paste")
			(net "GND")
		)
	)
	(footprint ""
		(layer "B.Cu")
		(at 449.723764 -76.697586 90)
		(property "Reference" "C2541"
			(at 0 0 90)
			(layer "B.SilkS")
			(hide yes)
			(effects
				(font
					(size 1.27 1.27)
				)
				(justify mirror)
			)
		)
		(property "Value" ""
			(at 0 0 90)
			(layer "B.Fab")
			(effects
				(font
					(size 1.27 1.27)
				)
				(justify mirror)
			)
		)
		(duplicate_pad_numbers_are_jumpers no)
		(fp_line
			(start 0.7874 -0.4064)
			(end -0.7874 -0.4064)
			(stroke
				(width 0.1524)
				(type default)
			)
			(layer "B.SilkS")
		)
		(fp_line
			(start -0.7874 -0.4064)
			(end -0.7874 0.4064)
			(stroke
				(width 0.1524)
				(type default)
			)
			(layer "B.SilkS")
		)
		(fp_line
			(start 0.7874 0.4064)
			(end 0.7874 -0.4064)
			(stroke
				(width 0.1524)
				(type default)
			)
			(layer "B.SilkS")
		)
		(fp_line
			(start -0.7874 0.4064)
			(end 0.7874 0.4064)
			(stroke
				(width 0.1524)
				(type default)
			)
			(layer "B.SilkS")
		)
		(fp_line
			(start 0.67945 -0.305054)
			(end 0.12065 -0.305054)
			(stroke
				(width 0.1)
				(type default)
			)
			(layer "B.Fab")
		)
		(fp_line
			(start 0.12065 -0.305054)
			(end 0.12065 -0.2794)
			(stroke
				(width 0.1)
				(type default)
			)
			(layer "B.Fab")
		)
		(fp_line
			(start -0.12065 -0.3048)
			(end -0.67945 -0.3048)
			(stroke
				(width 0.1)
				(type default)
			)
			(layer "B.Fab")
		)
		(fp_line
			(start -0.67945 -0.3048)
			(end -0.67945 0.3048)
			(stroke
				(width 0.1)
				(type default)
			)
			(layer "B.Fab")
		)
		(fp_line
			(start 0.12065 -0.2794)
			(end -0.12065 -0.2794)
			(stroke
				(width 0.1)
				(type default)
			)
			(layer "B.Fab")
		)
		(fp_line
			(start -0.12065 -0.2794)
			(end -0.12065 -0.3048)
			(stroke
				(width 0.1)
				(type default)
			)
			(layer "B.Fab")
		)
		(fp_line
			(start 0.12065 0.2794)
			(end 0.12065 0.3048)
			(stroke
				(width 0.1)
				(type default)
			)
			(layer "B.Fab")
		)
		(fp_line
			(start -0.120396 0.2794)
			(end 0.12065 0.2794)
			(stroke
				(width 0.1)
				(type default)
			)
			(layer "B.Fab")
		)
		(fp_line
			(start 0.67945 0.3048)
			(end 0.67945 -0.305054)
			(stroke
				(width 0.1)
				(type default)
			)
			(layer "B.Fab")
		)
		(fp_line
			(start 0.12065 0.3048)
			(end 0.67945 0.3048)
			(stroke
				(width 0.1)
				(type default)
			)
			(layer "B.Fab")
		)
		(fp_line
			(start -0.120396 0.3048)
			(end -0.120396 0.2794)
			(stroke
				(width 0.1)
				(type default)
			)
			(layer "B.Fab")
		)
		(fp_line
			(start -0.67945 0.3048)
			(end -0.120396 0.3048)
			(stroke
				(width 0.1)
				(type default)
			)
			(layer "B.Fab")
		)
		(pad "1" smd circle
			(at 0.40005 0 270)
			(size 0 0)
			(layers "B.Cu" "B.Mask" "B.Paste")
			(net "P3V3_AUX_EN")
		)
		(pad "2" smd circle
			(at -0.40005 0 270)
			(size 0 0)
			(layers "B.Cu" "B.Mask" "B.Paste")
			(net "GND")
		)
	)
)
